(kicad_pcb
	(version 20211014)
	(generator pcbnew)
	(general
    (thickness 1.6)
  )
	(paper "A4")
	(title_block
    (title "SA800U (Snapdragon 845) Baseboard")
    (date "2023-10-19")
    (rev "1.0.3")
    (company "Antmicro Ltd.")
    (comment 1 "www.antmicro.com")
		(comment 9 "footprints 120-127 of 589")
	)
	(layers
    (0 "F.Cu" signal)
    (1 "In1.Cu" power)
    (2 "In2.Cu" signal)
    (3 "In3.Cu" signal)
    (4 "In4.Cu" power)
    (31 "B.Cu" signal)
    (32 "B.Adhes" user "B.Adhesive")
    (33 "F.Adhes" user "F.Adhesive")
    (34 "B.Paste" user)
    (35 "F.Paste" user)
    (36 "B.SilkS" user "B.Silkscreen")
    (37 "F.SilkS" user "F.Silkscreen")
    (38 "B.Mask" user)
    (39 "F.Mask" user)
    (40 "Dwgs.User" user "User.Drawings")
    (41 "Cmts.User" user "User.Comments")
    (42 "Eco1.User" user "User.Eco1")
    (43 "Eco2.User" user "User.Eco2")
    (44 "Edge.Cuts" user)
    (45 "Margin" user)
    (46 "B.CrtYd" user "B.Courtyard")
    (47 "F.CrtYd" user "F.Courtyard")
    (48 "B.Fab" user)
    (49 "F.Fab" user)
  )
	(footprint "sa800u-baseboard-hw-footprints:C_0402_1005Metric" (layer "F.Cu")
    (tedit 616D63CF)
    (at 95.1 139.8 -90)
    (descr "Capacitor SMD 0402")
    (tags "capacitor SMD 0402")
    (property "Author" "Antmicro")
    (property "Dielectric" "X5R")
    (property "License" "Apache-2.0")
    (property "MPN" "GRM155R61H104KE14D")
    (property "Manufacturer" "Murata")
    (property "Sheetfile" "usb-c-interface.kicad_sch")
    (property "Sheetname" "USB-C Interface ")
    (property "Val" "100n")
    (property "Voltage" "50V")
    (attr smd)
    (fp_text reference "C60" (at -0.87 -0.39 -90) (layer "F.SilkS")
      (effects (font (size 0.7 0.7) (thickness 0.15)) (justify left bottom))
    )
    (fp_text value "C_100n_0402" (at 0 1.4 -90) (layer "F.Fab")
      (effects (font (size 0.7 0.7) (thickness 0.15)) (justify left bottom))
    )
    (fp_text user "License: Apache-2.0" (at -0.932 5.17 -90) (layer "F.Fab") hide
      (effects (font (size 0.7 0.7) (thickness 0.15)) (justify left bottom))
    )
    (fp_text user "${REFERENCE}" (at -0.932 3.168 -90) (layer "F.Fab") hide
      (effects (font (size 0.7 0.7) (thickness 0.15)) (justify left bottom))
    )
    (fp_text user "Author: Antmicro" (at -0.932 4.17 -90) (layer "F.Fab") hide
      (effects (font (size 0.7 0.7) (thickness 0.15)) (justify left bottom))
    )
    (fp_rect (start -0.94 -0.47) (end 0.94 0.47) (layer "F.CrtYd") (width 0.05) (fill none))
    (fp_rect (start -0.499 -0.249) (end 0.499 0.249) (layer "F.Fab") (width 0.15) (fill none))
    (pad "1" smd roundrect (at -0.484 0 270) (size 0.59 0.64) (layers "F.Cu" "F.Paste" "F.Mask") (roundrect_rratio 0.25)
      (net 11 "EDP_AUX_P") (pintype "passive"))
    (pad "2" smd roundrect (at 0.484 0 270) (size 0.59 0.64) (layers "F.Cu" "F.Paste" "F.Mask") (roundrect_rratio 0.25)
      (net 329 "/USB-C Interface /USB_SBU_NP_P") (pintype "passive"))
  )
	(footprint "sa800u-baseboard-hw-footprints:XQFN-10-1.4x1.8mm_P0.4mm" (layer "F.Cu")
    (tedit 6206D50C)
    (at 94.8 142.9 180)
    (property "Author" "Antmicro")
    (property "License" "Apache-2.0")
    (property "MPN" "NX3DV42GU,115")
    (property "Manufacturer" "NXP")
    (property "Sheetfile" "usb-c-interface.kicad_sch")
    (property "Sheetname" "USB-C Interface ")
    (attr smd)
    (fp_text reference "U7" (at -0.43 1.18 180) (layer "F.SilkS")
      (effects (font (size 0.7 0.7) (thickness 0.15)) (justify left bottom))
    )
    (fp_text value "NX3DV42GU" (at 0 2.3 180) (layer "F.Fab")
      (effects (font (size 0.7 0.7) (thickness 0.15)) (justify left bottom))
    )
    (fp_text user "Author: Antmicro" (at -1.2 6.299 180) (layer "F.Fab") hide
      (effects (font (size 0.7 0.7) (thickness 0.15)) (justify left bottom))
    )
    (fp_text user "License: Apache-2.0" (at -1.2 7.499 180) (layer "F.Fab") hide
      (effects (font (size 0.7 0.7) (thickness 0.15)) (justify left bottom))
    )
    (fp_text user "${REFERENCE}" (at -1.2 5.099 180) (layer "F.Fab") hide
      (effects (font (size 0.7 0.7) (thickness 0.15)) (justify left bottom))
    )
    (fp_line (start -0.802 0.998) (end -0.652 0.998) (layer "F.SilkS") (width 0.15))
    (fp_line (start 0.8 -1) (end 0.8 -0.5) (layer "F.SilkS") (width 0.15))
    (fp_line (start 0.8 0.998) (end 0.65 0.998) (layer "F.SilkS") (width 0.15))
    (fp_line (start -0.802 -1) (end -0.61 -1) (layer "F.SilkS") (width 0.15))
    (fp_line (start -0.802 0.998) (end -0.802 0.498) (layer "F.SilkS") (width 0.15))
    (fp_line (start 0.8 0.498) (end 0.8 0.998) (layer "F.SilkS") (width 0.15))
    (fp_line (start 0.8 -1) (end 0.65 -1) (layer "F.SilkS") (width 0.15))
    (fp_circle (center -1 -0.5) (end -0.95 -0.5) (layer "F.SilkS") (width 0.15) (fill solid))
    (fp_rect (start -1.1 -1.35) (end 1.1 1.35) (layer "F.CrtYd") (width 0.05) (fill none))
    (fp_line (start -0.6 -0.951) (end -0.75 -0.802) (layer "F.Fab") (width 0.15))
    (fp_line (start 0.748 -0.951) (end -0.6 -0.951) (layer "F.Fab") (width 0.15))
    (fp_line (start -0.75 0.949) (end -0.75 -0.802) (layer "F.Fab") (width 0.15))
    (fp_line (start 0.748 -0.951) (end 0.748 0.949) (layer "F.Fab") (width 0.15))
    (fp_line (start -0.75 0.949) (end 0.748 0.949) (layer "F.Fab") (width 0.15))
    (pad "1" smd rect (at -0.677 -0.202 270) (size 0.25 0.8) (drill (offset 0 0.05)) (layers "F.Cu" "F.Paste" "F.Mask")
      (net 330 "/USB-C Interface /USB1_SBU_N") (pinfunction "D+") (pintype "bidirectional"))
    (pad "2" smd rect (at -0.677 0.2 270) (size 0.25 0.7) (layers "F.Cu" "F.Paste" "F.Mask")
      (net 331 "/USB-C Interface /USB1_SBU_P") (pinfunction "D-") (pintype "bidirectional"))
    (pad "3" smd rect (at -0.402 0.925 180) (size 0.25 0.7) (layers "F.Cu" "F.Paste" "F.Mask")
      (net 1 "GND") (pinfunction "GND") (pintype "power_in"))
    (pad "4" smd rect (at 0 0.925 180) (size 0.25 0.7) (layers "F.Cu" "F.Paste" "F.Mask")
      (net 329 "/USB-C Interface /USB_SBU_NP_P") (pinfunction "HSD1-") (pintype "bidirectional"))
    (pad "5" smd rect (at 0.4 0.925 180) (size 0.25 0.7) (layers "F.Cu" "F.Paste" "F.Mask")
      (net 328 "/USB-C Interface /USB_SBU_NP_N") (pinfunction "HSD1+") (pintype "bidirectional"))
    (pad "6" smd rect (at 0.675 0.2 270) (size 0.25 0.7) (layers "F.Cu" "F.Paste" "F.Mask")
      (net 329 "/USB-C Interface /USB_SBU_NP_P") (pinfunction "HSD2-") (pintype "bidirectional"))
    (pad "7" smd rect (at 0.675 -0.202 270) (size 0.25 0.7) (layers "F.Cu" "F.Paste" "F.Mask")
      (net 328 "/USB-C Interface /USB_SBU_NP_N") (pinfunction "HSD2+") (pintype "bidirectional"))
    (pad "8" smd rect (at 0.4 -0.927 180) (size 0.25 0.7) (layers "F.Cu" "F.Paste" "F.Mask")
      (net 93 "SBU_SW_OE") (pinfunction "~{OE}") (pintype "input"))
    (pad "9" smd rect (at 0 -0.927 180) (size 0.25 0.7) (layers "F.Cu" "F.Paste" "F.Mask")
      (net 131 "3V3_SYS") (pinfunction "VCC") (pintype "power_in"))
    (pad "10" smd rect (at -0.402 -0.927 180) (size 0.25 0.7) (layers "F.Cu" "F.Paste" "F.Mask")
      (net 98 "SBU_SW_SEL") (pinfunction "SEL") (pintype "input"))
  )
	(footprint "sa800u-baseboard-hw-footprints:L_Murata_025020_0605Metric" (layer "F.Cu")
    (tedit 61AA2C4F)
    (at 152 118.5)
    (property "Author" "Antmicro")
    (property "License" "Apache-2.0")
    (property "MPN" "NFP0QHB242HS2D")
    (property "Manufacturer" "Murata")
    (property "Sheetfile" "lcm.kicad_sch")
    (property "Sheetname" "LCM")
    (attr smd)
    (fp_text reference "L11" (at -0.99 -0.72) (layer "F.SilkS")
      (effects (font (size 0.7 0.7) (thickness 0.15)) (justify left bottom))
    )
    (fp_text value "NFP0QHB242HS2D" (at 0 1.55) (layer "F.Fab")
      (effects (font (size 0.7 0.7) (thickness 0.15)) (justify left bottom))
    )
    (fp_text user "Author: Antmicro" (at -1.027 4.605) (layer "F.Fab") hide
      (effects (font (size 0.7 0.7) (thickness 0.15)) (justify left bottom))
    )
    (fp_text user "License: Apache-2.0" (at -1.027 5.805) (layer "F.Fab") hide
      (effects (font (size 0.7 0.7) (thickness 0.15)) (justify left bottom))
    )
    (fp_text user "${REFERENCE}" (at -1.027 3.406) (layer "F.Fab") hide
      (effects (font (size 0.7 0.7) (thickness 0.15)) (justify left bottom))
    )
    (fp_line (start 0.276 -0.45) (end -0.276 -0.45) (layer "F.SilkS") (width 0.15))
    (fp_line (start -0.276 0.45) (end 0.276 0.45) (layer "F.SilkS") (width 0.15))
    (fp_circle (center -0.5 -0.5) (end -0.449 -0.5) (layer "F.SilkS") (width 0.15) (fill solid))
    (fp_rect (start -0.5 -0.6) (end 0.5 0.6) (layer "F.CrtYd") (width 0.05) (fill none))
    (fp_line (start -0.277 -0.351) (end -0.277 0.349) (layer "F.Fab") (width 0.15))
    (fp_line (start 0.275 -0.351) (end -0.277 -0.351) (layer "F.Fab") (width 0.15))
    (fp_line (start -0.277 0.349) (end 0.275 0.349) (layer "F.Fab") (width 0.15))
    (fp_line (start 0.275 0.349) (end 0.275 -0.351) (layer "F.Fab") (width 0.15))
    (pad "1" smd rect (at -0.25 -0.24) (size 0.3 0.23) (layers "F.Cu" "F.Paste" "F.Mask")
      (net 318 "/LCM/DSI_LN3_L_N") (pinfunction "1") (pintype "passive"))
    (pad "2" smd rect (at 0.248 -0.24) (size 0.3 0.23) (layers "F.Cu" "F.Paste" "F.Mask")
      (net 90 "DSI0_LN3_N") (pinfunction "2") (pintype "passive"))
    (pad "3" smd rect (at 0.248 0.239) (size 0.3 0.23) (layers "F.Cu" "F.Paste" "F.Mask")
      (net 89 "DSI0_LN3_P") (pinfunction "3") (pintype "passive"))
    (pad "4" smd rect (at -0.25 0.239) (size 0.3 0.23) (layers "F.Cu" "F.Paste" "F.Mask")
      (net 317 "/LCM/DSI_LN3_L_P") (pinfunction "4") (pintype "passive"))
  )
	(footprint "sa800u-baseboard-hw-footprints:C_0402_1005Metric" (layer "F.Cu")
    (tedit 616D63CF)
    (at 112.85 109.4 180)
    (descr "Capacitor SMD 0402")
    (tags "capacitor SMD 0402")
    (property "Author" "Antmicro")
    (property "Dielectric" "X5R")
    (property "License" "Apache-2.0")
    (property "MPN" "GRM155R61H104KE14D")
    (property "Manufacturer" "Murata")
    (property "Sheetfile" "other-interfaces.kicad_sch")
    (property "Sheetname" "Other Interfaces")
    (property "Val" "100n")
    (property "Voltage" "50V")
    (attr smd)
    (fp_text reference "C117" (at 1.86 -1.33 180) (layer "F.SilkS")
      (effects (font (size 0.7 0.7) (thickness 0.15)) (justify left bottom))
    )
    (fp_text value "C_100n_0402" (at 0 1.4 180) (layer "F.Fab")
      (effects (font (size 0.7 0.7) (thickness 0.15)) (justify left bottom))
    )
    (fp_text user "License: Apache-2.0" (at -0.932 5.17 180) (layer "F.Fab") hide
      (effects (font (size 0.7 0.7) (thickness 0.15)) (justify left bottom))
    )
    (fp_text user "${REFERENCE}" (at -0.932 3.168 180) (layer "F.Fab") hide
      (effects (font (size 0.7 0.7) (thickness 0.15)) (justify left bottom))
    )
    (fp_text user "Author: Antmicro" (at -0.932 4.17 180) (layer "F.Fab") hide
      (effects (font (size 0.7 0.7) (thickness 0.15)) (justify left bottom))
    )
    (fp_rect (start -0.94 -0.47) (end 0.94 0.47) (layer "F.CrtYd") (width 0.05) (fill none))
    (fp_rect (start -0.499 -0.249) (end 0.499 0.249) (layer "F.Fab") (width 0.15) (fill none))
    (pad "1" smd roundrect (at -0.484 0 180) (size 0.59 0.64) (layers "F.Cu" "F.Paste" "F.Mask") (roundrect_rratio 0.25)
      (net 132 "VREG_S4A_1V8") (pintype "passive"))
    (pad "2" smd roundrect (at 0.484 0 180) (size 0.59 0.64) (layers "F.Cu" "F.Paste" "F.Mask") (roundrect_rratio 0.25)
      (net 1 "GND") (pintype "passive"))
  )
	(footprint "sa800u-baseboard-hw-footprints:C_0402_1005Metric" (layer "F.Cu")
    (tedit 616D63CF)
    (at 114.75 109.4)
    (descr "Capacitor SMD 0402")
    (tags "capacitor SMD 0402")
    (property "Author" "Antmicro")
    (property "Dielectric" "X5R")
    (property "License" "Apache-2.0")
    (property "MPN" "GRM155R61H104KE14D")
    (property "Manufacturer" "Murata")
    (property "Sheetfile" "other-interfaces.kicad_sch")
    (property "Sheetname" "Other Interfaces")
    (property "Val" "100n")
    (property "Voltage" "50V")
    (attr smd)
    (fp_text reference "C120" (at -1.05 1.29) (layer "F.SilkS")
      (effects (font (size 0.7 0.7) (thickness 0.15)) (justify left bottom))
    )
    (fp_text value "C_100n_0402" (at 0 1.4) (layer "F.Fab")
      (effects (font (size 0.7 0.7) (thickness 0.15)) (justify left bottom))
    )
    (fp_text user "License: Apache-2.0" (at -0.932 5.17) (layer "F.Fab") hide
      (effects (font (size 0.7 0.7) (thickness 0.15)) (justify left bottom))
    )
    (fp_text user "Author: Antmicro" (at -0.932 4.17) (layer "F.Fab") hide
      (effects (font (size 0.7 0.7) (thickness 0.15)) (justify left bottom))
    )
    (fp_text user "${REFERENCE}" (at -0.932 3.168) (layer "F.Fab") hide
      (effects (font (size 0.7 0.7) (thickness 0.15)) (justify left bottom))
    )
    (fp_rect (start -0.94 -0.47) (end 0.94 0.47) (layer "F.CrtYd") (width 0.05) (fill none))
    (fp_rect (start -0.499 -0.249) (end 0.499 0.249) (layer "F.Fab") (width 0.15) (fill none))
    (pad "1" smd roundrect (at -0.484 0) (size 0.59 0.64) (layers "F.Cu" "F.Paste" "F.Mask") (roundrect_rratio 0.25)
      (net 131 "3V3_SYS") (pintype "passive"))
    (pad "2" smd roundrect (at 0.484 0) (size 0.59 0.64) (layers "F.Cu" "F.Paste" "F.Mask") (roundrect_rratio 0.25)
      (net 1 "GND") (pintype "passive"))
  )
	(footprint "sa800u-baseboard-hw-footprints:BM04B-SRSS-TB-LF-SN" (layer "F.Cu")
    (tedit 616FBFD6)
    (at 146.2 85.9 -90)
    (property "Author" "Antmicro")
    (property "License" "Apache-2.0")
    (property "MPN" "BM04B-SRSS-TB(LF)(SN) ")
    (property "Manufacturer" "JST")
    (property "Sheetfile" "other-interfaces.kicad_sch")
    (property "Sheetname" "Other Interfaces")
    (attr smd)
    (fp_text reference "J9" (at 3.49 1.47 -90) (layer "F.SilkS")
      (effects (font (size 0.7 0.7) (thickness 0.15)) (justify left bottom))
    )
    (fp_text value "BM04B-SRSS-TB-LF-SN" (at 0.0508 3.302 -90) (layer "F.Fab")
      (effects (font (size 0.7 0.7) (thickness 0.15)) (justify left bottom))
    )
    (fp_text user "Author: Antmicro" (at -3.65 5.302 -90) (layer "F.Fab") hide
      (effects (font (size 0.7 0.7) (thickness 0.15)) (justify left bottom))
    )
    (fp_text user "License: Apache-2.0" (at -3.65 7.702 -90) (layer "F.Fab") hide
      (effects (font (size 0.7 0.7) (thickness 0.15)) (justify left bottom))
    )
    (fp_text user "${REFERENCE}" (at -3.65 6.502 -90) (layer "F.Fab") hide
      (effects (font (size 0.7 0.7) (thickness 0.15)) (justify left bottom))
    )
    (fp_line (start -1.7005 -1.8495) (end 1.7015 -1.8495) (layer "F.SilkS") (width 0.15))
    (fp_line (start -2.999 0.1765) (end -2.999 1.0505) (layer "F.SilkS") (width 0.15))
    (fp_line (start 2.9995 0.1765) (end 2.9995 1.0505) (layer "F.SilkS") (width 0.15))
    (fp_line (start -2.999 1.0505) (end -2.201 1.0505) (layer "F.SilkS") (width 0.15))
    (fp_line (start 2.9995 1.0505) (end 2.2015 1.0505) (layer "F.SilkS") (width 0.15))
    (fp_circle (center -2.1 2.1) (end -2.049 2.1) (layer "F.SilkS") (width 0.15) (fill solid))
    (fp_line (start -3.6495 2.3805) (end -3.6495 -2.1839) (layer "F.CrtYd") (width 0.05))
    (fp_line (start 3.6505 -2.1839) (end 3.6505 2.3805) (layer "F.CrtYd") (width 0.05))
    (fp_line (start 3.6505 2.3805) (end -3.6495 2.3805) (layer "F.CrtYd") (width 0.05))
    (fp_line (start -3.6495 -2.1839) (end 3.6505 -2.1839) (layer "F.CrtYd") (width 0.05))
    (fp_line (start 3.008 1.7785) (end -1.991 1.7785) (layer "F.Fab") (width 0.15))
    (fp_line (start -2.9995 -1.8495) (end 2.9995 -1.8495) (layer "F.Fab") (width 0.15))
    (fp_line (start 2.9995 -1.8495) (end 3.008 1.7785) (layer "F.Fab") (width 0.15))
    (fp_line (start -1.991 1.7785) (end -2.9995 0.9657) (layer "F.Fab") (width 0.15))
    (fp_line (start -2.9995 1.0165) (end -2.9995 -1.8495) (layer "F.Fab") (width 0.15))
    (pad "1" smd rect (at -1.4995 1.3765 270) (size 0.6 1.55) (layers "F.Cu" "F.Paste" "F.Mask")
      (net 1 "GND") (pinfunction "Pin_1") (pintype "passive"))
    (pad "2" smd rect (at -0.5015 1.3765 270) (size 0.6 1.55) (layers "F.Cu" "F.Paste" "F.Mask")
      (net 131 "3V3_SYS") (pinfunction "Pin_2") (pintype "passive"))
    (pad "3" smd rect (at 0.4995 1.3765 270) (size 0.6 1.55) (layers "F.Cu" "F.Paste" "F.Mask")
      (net 338 "/Other Interfaces/I2C10_SDA_3V3") (pinfunction "Pin_3") (pintype "passive"))
    (pad "4" smd rect (at 1.4995 1.3765 270) (size 0.6 1.55) (layers "F.Cu" "F.Paste" "F.Mask")
      (net 337 "/Other Interfaces/I2C10_SCL_3V3") (pinfunction "Pin_4") (pintype "passive"))
    (pad "MP" smd rect (at 2.8005 -1.1485 270) (size 1.2 1.8) (layers "F.Cu" "F.Paste" "F.Mask")
      (net 661 "unconnected-(J9-PadMP)") (pinfunction "MP") (pintype "passive+no_connect"))
    (pad "MP" smd rect (at -2.7995 -1.1485 270) (size 1.2 1.8) (layers "F.Cu" "F.Paste" "F.Mask")
      (net 661 "unconnected-(J9-PadMP)") (pinfunction "MP") (pintype "passive+no_connect"))
  )
	(footprint "sa800u-baseboard-hw-footprints:R_0402_1005Metric" (layer "F.Cu")
    (tedit 5FD9C158)
    (at 116.2 108.2)
    (descr "Resistor SMD 0402")
    (tags "resistor SMD 0402")
    (property "Author" "Antmicro")
    (property "License" "Apache-2.0")
    (property "MPN" "CR0402-FX-2001GLF")
    (property "Manufacturer" "Bourns")
    (property "Sheetfile" "other-interfaces.kicad_sch")
    (property "Sheetname" "Other Interfaces")
    (property "Tolerance" "1%")
    (property "Val" "2k")
    (attr smd)
    (fp_text reference "R103" (at 0.81 0.07) (layer "F.SilkS")
      (effects (font (size 0.7 0.7) (thickness 0.15)) (justify left bottom))
    )
    (fp_text value "R_2k_0402" (at 0 1.4) (layer "F.Fab")
      (effects (font (size 0.7 0.7) (thickness 0.15)) (justify left bottom))
    )
    (fp_text user "License: Apache-2.0" (at -0.95 5.169) (layer "F.Fab") hide
      (effects (font (size 0.7 0.7) (thickness 0.15)) (justify left bottom))
    )
    (fp_text user "${REFERENCE}" (at -0.95 3.168) (layer "F.Fab") hide
      (effects (font (size 0.7 0.7) (thickness 0.15)) (justify left bottom))
    )
    (fp_text user "Author: Antmicro" (at -0.95 4.169) (layer "F.Fab") hide
      (effects (font (size 0.7 0.7) (thickness 0.15)) (justify left bottom))
    )
    (fp_rect (start -0.93 -0.47) (end 0.93 0.47) (layer "F.CrtYd") (width 0.05) (fill none))
    (fp_rect (start -0.5 -0.25) (end 0.5 0.25) (layer "F.Fab") (width 0.15) (fill none))
    (pad "1" smd roundrect (at -0.485 0) (size 0.59 0.64) (layers "F.Cu" "F.Paste" "F.Mask") (roundrect_rratio 0.25)
      (net 337 "/Other Interfaces/I2C10_SCL_3V3") (pintype "passive"))
    (pad "2" smd roundrect (at 0.485 0) (size 0.59 0.64) (layers "F.Cu" "F.Paste" "F.Mask") (roundrect_rratio 0.25)
      (net 131 "3V3_SYS") (pintype "passive"))
  )
	(footprint "sa800u-baseboard-hw-footprints:R_0402_1005Metric" (layer "F.Cu")
    (tedit 5FD9C158)
    (at 116.2 107.2)
    (descr "Resistor SMD 0402")
    (tags "resistor SMD 0402")
    (property "Author" "Antmicro")
    (property "License" "Apache-2.0")
    (property "MPN" "CR0402-FX-2001GLF")
    (property "Manufacturer" "Bourns")
    (property "Sheetfile" "other-interfaces.kicad_sch")
    (property "Sheetname" "Other Interfaces")
    (property "Tolerance" "1%")
    (property "Val" "2k")
    (attr smd)
    (fp_text reference "R104" (at 0.81 0.07) (layer "F.SilkS")
      (effects (font (size 0.7 0.7) (thickness 0.15)) (justify left bottom))
    )
    (fp_text value "R_2k_0402" (at 0 1.4) (layer "F.Fab")
      (effects (font (size 0.7 0.7) (thickness 0.15)) (justify left bottom))
    )
    (fp_text user "${REFERENCE}" (at -0.95 3.168) (layer "F.Fab") hide
      (effects (font (size 0.7 0.7) (thickness 0.15)) (justify left bottom))
    )
    (fp_text user "Author: Antmicro" (at -0.95 4.169) (layer "F.Fab") hide
      (effects (font (size 0.7 0.7) (thickness 0.15)) (justify left bottom))
    )
    (fp_text user "License: Apache-2.0" (at -0.95 5.169) (layer "F.Fab") hide
      (effects (font (size 0.7 0.7) (thickness 0.15)) (justify left bottom))
    )
    (fp_rect (start -0.93 -0.47) (end 0.93 0.47) (layer "F.CrtYd") (width 0.05) (fill none))
    (fp_rect (start -0.5 -0.25) (end 0.5 0.25) (layer "F.Fab") (width 0.15) (fill none))
    (pad "1" smd roundrect (at -0.485 0) (size 0.59 0.64) (layers "F.Cu" "F.Paste" "F.Mask") (roundrect_rratio 0.25)
      (net 338 "/Other Interfaces/I2C10_SDA_3V3") (pintype "passive"))
    (pad "2" smd roundrect (at 0.485 0) (size 0.59 0.64) (layers "F.Cu" "F.Paste" "F.Mask") (roundrect_rratio 0.25)
      (net 131 "3V3_SYS") (pintype "passive"))
  )
)
